(kicad_pcb
	(version 20260206)
	(generator "pcbnew")
	(generator_version "10.0")
	(general
		(thickness 1.6)
		(legacy_teardrops no)
	)
	(paper "A4")
	(title_block
		(title "04192023_DAF0TMB3IC0_F0TG_MB_C_brd_V02_OCP.brd")
		(comment 1 "Grand Teton / footprints 3761-3767 of 8354")
	)
	(layers
		(0 "F.Cu" signal "TOP")
		(4 "In1.Cu" signal "GND")
		(6 "In2.Cu" signal "IN1")
		(8 "In3.Cu" signal "GND1")
		(10 "In4.Cu" signal "IN2")
		(12 "In5.Cu" signal "GND2")
		(14 "In6.Cu" signal "IN3")
		(16 "In7.Cu" signal "GND3")
		(18 "In8.Cu" signal "VCC")
		(20 "In9.Cu" signal "VCC1")
		(22 "In10.Cu" signal "GND4")
		(24 "In11.Cu" signal "IN4")
		(26 "In12.Cu" signal "GND5")
		(28 "In13.Cu" signal "IN5")
		(30 "In14.Cu" signal "GND6")
		(32 "In15.Cu" signal "IN6")
		(34 "In16.Cu" signal "GND7")
		(2 "B.Cu" signal "BOTTOM")
		(9 "F.Adhes" user "F.Adhesive")
		(11 "B.Adhes" user "B.Adhesive")
		(13 "F.Paste" user "Package Geometry/Pastemask Top")
		(15 "B.Paste" user "Package Geometry/Pastemask Bottom")
		(5 "F.SilkS" user "Ref Des/Silkscreen Top")
		(7 "B.SilkS" user "Ref Des/Silkscreen Bottom")
		(1 "F.Mask" user "Board Geometry/Soldermask Top")
		(3 "B.Mask" user "Board Geometry/Soldermask Bottom")
		(17 "Dwgs.User" user "User.Drawings")
		(19 "Cmts.User" user "User.Comments")
		(21 "Eco1.User" user "User.Eco1")
		(23 "Eco2.User" user "User.Eco2")
		(25 "Edge.Cuts" user "Board Geometry/Outline")
		(27 "Margin" user)
		(31 "F.CrtYd" user "Package Geometry/Place Bound Top")
		(29 "B.CrtYd" user "Package Geometry/Place Bound Bottom")
		(35 "F.Fab" user "Ref Des/Assembly Top")
		(33 "B.Fab" user "Ref Des/Assembly Bottom")
	)
	(footprint ""
		(layer "F.Cu")
		(at 435.80812 -45.025056 90)
		(property "Reference" "PL8045"
			(at -1.629156 -3.891026 90)
			(unlocked yes)
			(layer "F.SilkS")
			(effects
				(font
					(size 0.7874 0.5842)
					(thickness 0.1524)
				)
				(justify left)
			)
		)
		(property "Value" ""
			(at 0 0 90)
			(layer "F.Fab")
			(effects
				(font
					(size 1.27 1.27)
				)
			)
		)
		(duplicate_pad_numbers_are_jumpers no)
		(fp_line
			(start 2.249932 -2.249932)
			(end 2.249932 -1.3843)
			(stroke
				(width 0.1524)
				(type default)
			)
			(layer "F.SilkS")
		)
		(fp_line
			(start -2.249932 -2.249932)
			(end 2.249932 -2.249932)
			(stroke
				(width 0.1524)
				(type default)
			)
			(layer "F.SilkS")
		)
		(fp_line
			(start -2.249932 -1.3843)
			(end -2.249932 -2.249932)
			(stroke
				(width 0.1524)
				(type default)
			)
			(layer "F.SilkS")
		)
		(fp_line
			(start 2.249932 1.3843)
			(end 2.249932 2.249932)
			(stroke
				(width 0.1524)
				(type default)
			)
			(layer "F.SilkS")
		)
		(fp_line
			(start 2.249932 2.249932)
			(end -2.249932 2.249932)
			(stroke
				(width 0.1524)
				(type default)
			)
			(layer "F.SilkS")
		)
		(fp_line
			(start -2.249932 2.249932)
			(end -2.249932 1.3843)
			(stroke
				(width 0.1524)
				(type default)
			)
			(layer "F.SilkS")
		)
		(fp_line
			(start 2.249932 -2.249932)
			(end 2.249932 2.249932)
			(stroke
				(width 0.1)
				(type default)
			)
			(layer "F.Fab")
		)
		(fp_line
			(start -2.249932 -2.249932)
			(end 2.249932 -2.249932)
			(stroke
				(width 0.1)
				(type default)
			)
			(layer "F.Fab")
		)
		(fp_line
			(start 2.249932 2.249932)
			(end -2.249932 2.249932)
			(stroke
				(width 0.1)
				(type default)
			)
			(layer "F.Fab")
		)
		(fp_line
			(start -2.249932 2.249932)
			(end -2.249932 -2.249932)
			(stroke
				(width 0.1)
				(type default)
			)
			(layer "F.Fab")
		)
		(pad "1" smd rect
			(at -1.82499 0 90)
			(size 1.0668 2.5146)
			(layers "F.Cu" "F.Mask" "F.Paste")
			(net "P12V_AUX")
		)
		(pad "2" smd rect
			(at 1.82499 0 90)
			(size 1.0668 2.5146)
			(layers "F.Cu" "F.Mask" "F.Paste")
			(net "SW_P3V3_AUX_FLT")
		)
	)
	(footprint ""
		(layer "F.Cu")
		(at 142.074392 -401.884896 90)
		(property "Reference" "C7040"
			(at 0 0 90)
			(layer "F.SilkS")
			(hide yes)
			(effects
				(font
					(size 1.27 1.27)
				)
			)
		)
		(property "Value" ""
			(at 0 0 90)
			(layer "F.Fab")
			(effects
				(font
					(size 1.27 1.27)
				)
			)
		)
		(duplicate_pad_numbers_are_jumpers no)
		(fp_line
			(start 1.524 -0.762)
			(end 1.524 0.762)
			(stroke
				(width 0.1524)
				(type default)
			)
			(layer "F.SilkS")
		)
		(fp_line
			(start -1.524 -0.762)
			(end 1.524 -0.762)
			(stroke
				(width 0.1524)
				(type default)
			)
			(layer "F.SilkS")
		)
		(fp_line
			(start 1.524 0.762)
			(end -1.524 0.762)
			(stroke
				(width 0.1524)
				(type default)
			)
			(layer "F.SilkS")
		)
		(fp_line
			(start -1.524 0.762)
			(end -1.524 -0.762)
			(stroke
				(width 0.1524)
				(type default)
			)
			(layer "F.SilkS")
		)
		(fp_line
			(start 1.1049 -0.724916)
			(end -1.1049 -0.724916)
			(stroke
				(width 0.1)
				(type default)
			)
			(layer "F.Fab")
		)
		(fp_line
			(start -1.1049 -0.724916)
			(end -1.1049 0.724916)
			(stroke
				(width 0.1)
				(type default)
			)
			(layer "F.Fab")
		)
		(fp_line
			(start 1.1049 0.724916)
			(end 1.1049 -0.724916)
			(stroke
				(width 0.1)
				(type default)
			)
			(layer "F.Fab")
		)
		(fp_line
			(start -1.1049 0.724916)
			(end 1.1049 0.724916)
			(stroke
				(width 0.1)
				(type default)
			)
			(layer "F.Fab")
		)
		(pad "1" smd rect
			(at -0.889 0 270)
			(size 1.016 1.27)
			(layers "F.Cu" "F.Mask" "F.Paste")
			(net "P0V9_CPU1_RT_2D")
		)
		(pad "2" smd rect
			(at 0.889 0 270)
			(size 1.016 1.27)
			(layers "F.Cu" "F.Mask" "F.Paste")
			(net "GND")
		)
	)
	(footprint ""
		(layer "F.Cu")
		(at 46.355 -38.354)
		(property "Reference" "U32"
			(at -2.017776 -2.360422 0)
			(unlocked yes)
			(layer "F.SilkS")
			(effects
				(font
					(size 0.7874 0.5842)
					(thickness 0.1524)
				)
			)
		)
		(property "Value" ""
			(at 0 0 0)
			(layer "F.Fab")
			(effects
				(font
					(size 1.27 1.27)
				)
			)
		)
		(duplicate_pad_numbers_are_jumpers no)
		(fp_line
			(start -1.949958 -1.610106)
			(end 1.949958 -1.610106)
			(stroke
				(width 0.1524)
				(type default)
			)
			(layer "F.SilkS")
		)
		(fp_line
			(start -1.949958 1.610106)
			(end -1.949958 -1.610106)
			(stroke
				(width 0.1524)
				(type default)
			)
			(layer "F.SilkS")
		)
		(fp_line
			(start 1.949958 -1.560068)
			(end 1.949958 1.610106)
			(stroke
				(width 0.1524)
				(type default)
			)
			(layer "F.SilkS")
		)
		(fp_line
			(start 1.949958 1.610106)
			(end -1.949958 1.610106)
			(stroke
				(width 0.1524)
				(type default)
			)
			(layer "F.SilkS")
		)
		(fp_line
			(start -0.750062 -1.560068)
			(end 0.750062 -1.560068)
			(stroke
				(width 0.1)
				(type default)
			)
			(layer "F.Fab")
		)
		(fp_line
			(start -0.750062 1.560068)
			(end -0.750062 -1.560068)
			(stroke
				(width 0.1)
				(type default)
			)
			(layer "F.Fab")
		)
		(fp_line
			(start 0.750062 -1.560068)
			(end 0.750062 1.560068)
			(stroke
				(width 0.1)
				(type default)
			)
			(layer "F.Fab")
		)
		(fp_line
			(start 0.750062 1.560068)
			(end -0.750062 1.560068)
			(stroke
				(width 0.1)
				(type default)
			)
			(layer "F.Fab")
		)
		(pad "D" smd rect
			(at 1.100074 0 270)
			(size 1.016 1.4224)
			(layers "F.Cu" "F.Mask" "F.Paste")
			(net "HP_LVC3_OCP_V3_2_PRSNT2")
		)
		(pad "G" smd rect
			(at -1.100074 -0.94996 270)
			(size 1.016 1.4224)
			(layers "F.Cu" "F.Mask" "F.Paste")
			(net "HP_LVC3_OCP_V3_2_PRSNT2_N")
		)
		(pad "S" smd rect
			(at -1.100074 0.94996 270)
			(size 1.016 1.4224)
			(layers "F.Cu" "F.Mask" "F.Paste")
			(net "GND")
		)
	)
	(footprint ""
		(layer "F.Cu")
		(at 361.046014 -258.795012)
		(property "Reference" "C2527"
			(at 0 0 0)
			(layer "F.SilkS")
			(hide yes)
			(effects
				(font
					(size 1.27 1.27)
				)
			)
		)
		(property "Value" ""
			(at 0 0 0)
			(layer "F.Fab")
			(effects
				(font
					(size 1.27 1.27)
				)
			)
		)
		(duplicate_pad_numbers_are_jumpers no)
		(fp_line
			(start -0.7874 -0.4064)
			(end 0.7874 -0.4064)
			(stroke
				(width 0.1524)
				(type default)
			)
			(layer "F.SilkS")
		)
		(fp_line
			(start -0.7874 0.4064)
			(end -0.7874 -0.4064)
			(stroke
				(width 0.1524)
				(type default)
			)
			(layer "F.SilkS")
		)
		(fp_line
			(start 0.7874 -0.4064)
			(end 0.7874 0.4064)
			(stroke
				(width 0.1524)
				(type default)
			)
			(layer "F.SilkS")
		)
		(fp_line
			(start 0.7874 0.4064)
			(end -0.7874 0.4064)
			(stroke
				(width 0.1524)
				(type default)
			)
			(layer "F.SilkS")
		)
		(fp_line
			(start -0.67945 -0.305054)
			(end -0.12065 -0.305054)
			(stroke
				(width 0.1)
				(type default)
			)
			(layer "F.Fab")
		)
		(fp_line
			(start -0.67945 0.3048)
			(end -0.67945 -0.305054)
			(stroke
				(width 0.1)
				(type default)
			)
			(layer "F.Fab")
		)
		(fp_line
			(start -0.12065 -0.305054)
			(end -0.12065 -0.2794)
			(stroke
				(width 0.1)
				(type default)
			)
			(layer "F.Fab")
		)
		(fp_line
			(start -0.12065 -0.2794)
			(end 0.12065 -0.2794)
			(stroke
				(width 0.1)
				(type default)
			)
			(layer "F.Fab")
		)
		(fp_line
			(start -0.12065 0.2794)
			(end -0.12065 0.3048)
			(stroke
				(width 0.1)
				(type default)
			)
			(layer "F.Fab")
		)
		(fp_line
			(start -0.12065 0.3048)
			(end -0.67945 0.3048)
			(stroke
				(width 0.1)
				(type default)
			)
			(layer "F.Fab")
		)
		(fp_line
			(start 0.120396 0.2794)
			(end -0.12065 0.2794)
			(stroke
				(width 0.1)
				(type default)
			)
			(layer "F.Fab")
		)
		(fp_line
			(start 0.120396 0.3048)
			(end 0.120396 0.2794)
			(stroke
				(width 0.1)
				(type default)
			)
			(layer "F.Fab")
		)
		(fp_line
			(start 0.12065 -0.3048)
			(end 0.67945 -0.3048)
			(stroke
				(width 0.1)
				(type default)
			)
			(layer "F.Fab")
		)
		(fp_line
			(start 0.12065 -0.2794)
			(end 0.12065 -0.3048)
			(stroke
				(width 0.1)
				(type default)
			)
			(layer "F.Fab")
		)
		(fp_line
			(start 0.67945 -0.3048)
			(end 0.67945 0.3048)
			(stroke
				(width 0.1)
				(type default)
			)
			(layer "F.Fab")
		)
		(fp_line
			(start 0.67945 0.3048)
			(end 0.120396 0.3048)
			(stroke
				(width 0.1)
				(type default)
			)
			(layer "F.Fab")
		)
		(pad "1" smd circle
			(at -0.40005 0)
			(size 0 0)
			(layers "F.Cu" "F.Mask" "F.Paste")
			(net "PVDDCR_SOC_P0")
		)
		(pad "2" smd circle
			(at 0.40005 0)
			(size 0 0)
			(layers "F.Cu" "F.Mask" "F.Paste")
			(net "GND")
		)
	)
	(footprint ""
		(layer "F.Cu")
		(at 156.83484 -93.174058 180)
		(property "Reference" "R3305"
			(at 0 0 180)
			(layer "F.SilkS")
			(hide yes)
			(effects
				(font
					(size 1.27 1.27)
				)
			)
		)
		(property "Value" ""
			(at 0 0 180)
			(layer "F.Fab")
			(effects
				(font
					(size 1.27 1.27)
				)
			)
		)
		(duplicate_pad_numbers_are_jumpers no)
		(fp_line
			(start 0.7874 0.4064)
			(end -0.7874 0.4064)
			(stroke
				(width 0.1524)
				(type default)
			)
			(layer "F.SilkS")
		)
		(fp_line
			(start 0.7874 -0.4064)
			(end 0.7874 0.4064)
			(stroke
				(width 0.1524)
				(type default)
			)
			(layer "F.SilkS")
		)
		(fp_line
			(start -0.7874 0.4064)
			(end -0.7874 -0.4064)
			(stroke
				(width 0.1524)
				(type default)
			)
			(layer "F.SilkS")
		)
		(fp_line
			(start -0.7874 -0.4064)
			(end 0.7874 -0.4064)
			(stroke
				(width 0.1524)
				(type default)
			)
			(layer "F.SilkS")
		)
		(fp_line
			(start 0.67945 0.3048)
			(end 0.120396 0.3048)
			(stroke
				(width 0.1)
				(type default)
			)
			(layer "F.Fab")
		)
		(fp_line
			(start 0.67945 -0.3048)
			(end 0.67945 0.3048)
			(stroke
				(width 0.1)
				(type default)
			)
			(layer "F.Fab")
		)
		(fp_line
			(start 0.12065 -0.2794)
			(end 0.12065 -0.3048)
			(stroke
				(width 0.1)
				(type default)
			)
			(layer "F.Fab")
		)
		(fp_line
			(start 0.12065 -0.3048)
			(end 0.67945 -0.3048)
			(stroke
				(width 0.1)
				(type default)
			)
			(layer "F.Fab")
		)
		(fp_line
			(start 0.120396 0.3048)
			(end 0.120396 0.2794)
			(stroke
				(width 0.1)
				(type default)
			)
			(layer "F.Fab")
		)
		(fp_line
			(start 0.120396 0.2794)
			(end -0.12065 0.2794)
			(stroke
				(width 0.1)
				(type default)
			)
			(layer "F.Fab")
		)
		(fp_line
			(start -0.12065 0.3048)
			(end -0.67945 0.3048)
			(stroke
				(width 0.1)
				(type default)
			)
			(layer "F.Fab")
		)
		(fp_line
			(start -0.12065 0.2794)
			(end -0.12065 0.3048)
			(stroke
				(width 0.1)
				(type default)
			)
			(layer "F.Fab")
		)
		(fp_line
			(start -0.12065 -0.2794)
			(end 0.12065 -0.2794)
			(stroke
				(width 0.1)
				(type default)
			)
			(layer "F.Fab")
		)
		(fp_line
			(start -0.12065 -0.305054)
			(end -0.12065 -0.2794)
			(stroke
				(width 0.1)
				(type default)
			)
			(layer "F.Fab")
		)
		(fp_line
			(start -0.67945 0.3048)
			(end -0.67945 -0.305054)
			(stroke
				(width 0.1)
				(type default)
			)
			(layer "F.Fab")
		)
		(fp_line
			(start -0.67945 -0.305054)
			(end -0.12065 -0.305054)
			(stroke
				(width 0.1)
				(type default)
			)
			(layer "F.Fab")
		)
		(pad "1" smd circle
			(at -0.40005 0 180)
			(size 0 0)
			(layers "F.Cu" "F.Mask" "F.Paste")
			(net "OCP_SFF_RBT_ARB_IN_MUX1")
		)
		(pad "2" smd circle
			(at 0.40005 0 180)
			(size 0 0)
			(layers "F.Cu" "F.Mask" "F.Paste")
			(net "OCP_SFF_RBT_ARB_IN_MUX1_R")
		)
	)
	(footprint ""
		(layer "F.Cu")
		(at 259.842 -102.108 180)
		(property "Reference" "C8006"
			(at 0 0 180)
			(layer "F.SilkS")
			(hide yes)
			(effects
				(font
					(size 1.27 1.27)
				)
			)
		)
		(property "Value" ""
			(at 0 0 180)
			(layer "F.Fab")
			(effects
				(font
					(size 1.27 1.27)
				)
			)
		)
		(duplicate_pad_numbers_are_jumpers no)
		(fp_line
			(start 0.7874 0.4064)
			(end -0.7874 0.4064)
			(stroke
				(width 0.1524)
				(type default)
			)
			(layer "F.SilkS")
		)
		(fp_line
			(start 0.7874 -0.4064)
			(end 0.7874 0.4064)
			(stroke
				(width 0.1524)
				(type default)
			)
			(layer "F.SilkS")
		)
		(fp_line
			(start -0.7874 0.4064)
			(end -0.7874 -0.4064)
			(stroke
				(width 0.1524)
				(type default)
			)
			(layer "F.SilkS")
		)
		(fp_line
			(start -0.7874 -0.4064)
			(end 0.7874 -0.4064)
			(stroke
				(width 0.1524)
				(type default)
			)
			(layer "F.SilkS")
		)
		(fp_line
			(start 0.67945 0.3048)
			(end 0.120396 0.3048)
			(stroke
				(width 0.1)
				(type default)
			)
			(layer "F.Fab")
		)
		(fp_line
			(start 0.67945 -0.3048)
			(end 0.67945 0.3048)
			(stroke
				(width 0.1)
				(type default)
			)
			(layer "F.Fab")
		)
		(fp_line
			(start 0.12065 -0.2794)
			(end 0.12065 -0.3048)
			(stroke
				(width 0.1)
				(type default)
			)
			(layer "F.Fab")
		)
		(fp_line
			(start 0.12065 -0.3048)
			(end 0.67945 -0.3048)
			(stroke
				(width 0.1)
				(type default)
			)
			(layer "F.Fab")
		)
		(fp_line
			(start 0.120396 0.3048)
			(end 0.120396 0.2794)
			(stroke
				(width 0.1)
				(type default)
			)
			(layer "F.Fab")
		)
		(fp_line
			(start 0.120396 0.2794)
			(end -0.12065 0.2794)
			(stroke
				(width 0.1)
				(type default)
			)
			(layer "F.Fab")
		)
		(fp_line
			(start -0.12065 0.3048)
			(end -0.67945 0.3048)
			(stroke
				(width 0.1)
				(type default)
			)
			(layer "F.Fab")
		)
		(fp_line
			(start -0.12065 0.2794)
			(end -0.12065 0.3048)
			(stroke
				(width 0.1)
				(type default)
			)
			(layer "F.Fab")
		)
		(fp_line
			(start -0.12065 -0.2794)
			(end 0.12065 -0.2794)
			(stroke
				(width 0.1)
				(type default)
			)
			(layer "F.Fab")
		)
		(fp_line
			(start -0.12065 -0.305054)
			(end -0.12065 -0.2794)
			(stroke
				(width 0.1)
				(type default)
			)
			(layer "F.Fab")
		)
		(fp_line
			(start -0.67945 0.3048)
			(end -0.67945 -0.305054)
			(stroke
				(width 0.1)
				(type default)
			)
			(layer "F.Fab")
		)
		(fp_line
			(start -0.67945 -0.305054)
			(end -0.12065 -0.305054)
			(stroke
				(width 0.1)
				(type default)
			)
			(layer "F.Fab")
		)
		(pad "1" smd circle
			(at -0.40005 0 180)
			(size 0 0)
			(layers "F.Cu" "F.Mask" "F.Paste")
			(net "JTAG_BMC_R_D_OE")
		)
		(pad "2" smd circle
			(at 0.40005 0 180)
			(size 0 0)
			(layers "F.Cu" "F.Mask" "F.Paste")
			(net "GND")
		)
	)
	(footprint ""
		(layer "F.Cu")
		(at 213.416134 -47.335948 90)
		(property "Reference" "R3589"
			(at 0 0 90)
			(layer "F.SilkS")
			(hide yes)
			(effects
				(font
					(size 1.27 1.27)
				)
			)
		)
		(property "Value" ""
			(at 0 0 90)
			(layer "F.Fab")
			(effects
				(font
					(size 1.27 1.27)
				)
			)
		)
		(duplicate_pad_numbers_are_jumpers no)
		(fp_line
			(start 0.7874 -0.4064)
			(end 0.7874 0.4064)
			(stroke
				(width 0.1524)
				(type default)
			)
			(layer "F.SilkS")
		)
		(fp_line
			(start -0.7874 -0.4064)
			(end 0.7874 -0.4064)
			(stroke
				(width 0.1524)
				(type default)
			)
			(layer "F.SilkS")
		)
		(fp_line
			(start 0.7874 0.4064)
			(end -0.7874 0.4064)
			(stroke
				(width 0.1524)
				(type default)
			)
			(layer "F.SilkS")
		)
		(fp_line
			(start -0.7874 0.4064)
			(end -0.7874 -0.4064)
			(stroke
				(width 0.1524)
				(type default)
			)
			(layer "F.SilkS")
		)
		(fp_line
			(start -0.12065 -0.305054)
			(end -0.12065 -0.2794)
			(stroke
				(width 0.1)
				(type default)
			)
			(layer "F.Fab")
		)
		(fp_line
			(start -0.67945 -0.305054)
			(end -0.12065 -0.305054)
			(stroke
				(width 0.1)
				(type default)
			)
			(layer "F.Fab")
		)
		(fp_line
			(start 0.67945 -0.3048)
			(end 0.67945 0.3048)
			(stroke
				(width 0.1)
				(type default)
			)
			(layer "F.Fab")
		)
		(fp_line
			(start 0.12065 -0.3048)
			(end 0.67945 -0.3048)
			(stroke
				(width 0.1)
				(type default)
			)
			(layer "F.Fab")
		)
		(fp_line
			(start 0.12065 -0.2794)
			(end 0.12065 -0.3048)
			(stroke
				(width 0.1)
				(type default)
			)
			(layer "F.Fab")
		)
		(fp_line
			(start -0.12065 -0.2794)
			(end 0.12065 -0.2794)
			(stroke
				(width 0.1)
				(type default)
			)
			(layer "F.Fab")
		)
		(fp_line
			(start 0.120396 0.2794)
			(end -0.12065 0.2794)
			(stroke
				(width 0.1)
				(type default)
			)
			(layer "F.Fab")
		)
		(fp_line
			(start -0.12065 0.2794)
			(end -0.12065 0.3048)
			(stroke
				(width 0.1)
				(type default)
			)
			(layer "F.Fab")
		)
		(fp_line
			(start 0.67945 0.3048)
			(end 0.120396 0.3048)
			(stroke
				(width 0.1)
				(type default)
			)
			(layer "F.Fab")
		)
		(fp_line
			(start 0.120396 0.3048)
			(end 0.120396 0.2794)
			(stroke
				(width 0.1)
				(type default)
			)
			(layer "F.Fab")
		)
		(fp_line
			(start -0.12065 0.3048)
			(end -0.67945 0.3048)
			(stroke
				(width 0.1)
				(type default)
			)
			(layer "F.Fab")
		)
		(fp_line
			(start -0.67945 0.3048)
			(end -0.67945 -0.305054)
			(stroke
				(width 0.1)
				(type default)
			)
			(layer "F.Fab")
		)
		(pad "1" smd circle
			(at -0.40005 0 90)
			(size 0 0)
			(layers "F.Cu" "F.Mask" "F.Paste")
			(net "SMB_INA230_3V3AUX_SDA")
		)
		(pad "2" smd circle
			(at 0.40005 0 90)
			(size 0 0)
			(layers "F.Cu" "F.Mask" "F.Paste")
			(net "SMB_INA230_2_3V3AUX_SDA_R")
		)
	)
)
